# BASEBOARD_FAB2 (Tioga Pass) — schematic netlist excerpt (pin names and nets, part order shuffled) for the footprints in the layout excerpt that follows; sources: Cadence DE-HDL packaged netlist, KiCad conversion of Wiwynn_Tioga_Pass_MB.brd

C5P3  CAP  100UF 4V 20% X5R  pkg 0805  page 220 : A = PVDDQ_DEF ; B = GND

U3P1  GTL2014  IC  pkg SM  page 96
  DIR  = PU_GTL2014_1_DIR
  B0  = PWRGD_CPU0_DRAMPWROK_DEF_G
  B1  = PWRGD_CPU0_DRAMPWROK_ABC_G
  VREF  = PD_GTL2014_1_VREF
  B2  = RST_CPU0_G_N
  B3  = PWRGD_CPU0_G
  GND(0)  = GND
  GND(1)  = GND
  A3  = PWRGD_CPU0_LVC3
  A2  = RST_CPU0_LVC3_N
  GND(2)  = GND
  A1  = PWRGD_DRAMPWRGD
  A0  = PWRGD_DRAMPWRGD
  VCC  = P3V3_STBY

(kicad_pcb
	(version 20260206)
	(generator "pcbnew")
	(generator_version "10.0")
	(general
		(thickness 1.6)
		(legacy_teardrops no)
	)
	(paper "A4")
	(title_block
		(title "Wiwynn_Tioga_Pass_MB.brd")
		(comment 1 "Tioga Pass / footprints 4042-4043 of 4770")
	)
	(layers
		(0 "F.Cu" signal "TOP")
		(4 "In1.Cu" signal "L2GND")
		(6 "In2.Cu" signal "L3")
		(8 "In3.Cu" signal "L4GND")
		(10 "In4.Cu" signal "L5")
		(12 "In5.Cu" signal "L6GND")
		(14 "In6.Cu" signal "L7VCC")
		(16 "In7.Cu" signal "L8VCC")
		(18 "In8.Cu" signal "L9GND")
		(20 "In9.Cu" signal "L10")
		(22 "In10.Cu" signal "L11GND")
		(24 "In11.Cu" signal "L12")
		(26 "In12.Cu" signal "L13GND")
		(2 "B.Cu" signal "BOTTOM")
		(9 "F.Adhes" user "F.Adhesive")
		(11 "B.Adhes" user "B.Adhesive")
		(13 "F.Paste" user "Package Geometry/Pastemask Top")
		(15 "B.Paste" user "Package Geometry/Pastemask Bottom")
		(5 "F.SilkS" user "Ref Des/Silkscreen Top")
		(7 "B.SilkS" user "Ref Des/Silkscreen Bottom")
		(1 "F.Mask" user "Board Geometry/Soldermask Top")
		(3 "B.Mask" user "Board Geometry/Soldermask Bottom")
		(17 "Dwgs.User" user "User.Drawings")
		(19 "Cmts.User" user "User.Comments")
		(21 "Eco1.User" user "User.Eco1")
		(23 "Eco2.User" user "User.Eco2")
		(25 "Edge.Cuts" user "Board Geometry/Outline")
		(27 "Margin" user)
		(31 "F.CrtYd" user "Package Geometry/Place Bound Top")
		(29 "B.CrtYd" user "Package Geometry/Place Bound Bottom")
		(35 "F.Fab" user "Ref Des/Assembly Top")
		(33 "B.Fab" user "Ref Des/Assembly Bottom")
	)
	(footprint ""
		(layer "B.Cu")
		(at 369.8875 -55.16372)
		(property "Reference" "U3P1"
			(at -4.578096 -1.320292 180)
			(unlocked yes)
			(layer "B.SilkS")
			(effects
				(font
					(size 0.7874 0.5842)
					(thickness 0.1524)
				)
				(justify left mirror)
			)
		)
		(property "Value" ""
			(at 0 0 0)
			(layer "B.Fab")
			(effects
				(font
					(size 1.27 1.27)
				)
				(justify mirror)
			)
		)
		(duplicate_pad_numbers_are_jumpers no)
		(fp_line
			(start -4.4323 -0.64008)
			(end -4.4323 4.52628)
			(stroke
				(width 0.1524)
				(type default)
			)
			(layer "B.SilkS")
		)
		(fp_line
			(start -4.4323 4.52628)
			(end -1.5367 4.52628)
			(stroke
				(width 0.1524)
				(type default)
			)
			(layer "B.SilkS")
		)
		(fp_line
			(start -3.302 0.49022)
			(end -3.302 -0.64008)
			(stroke
				(width 0.1524)
				(type default)
			)
			(layer "B.SilkS")
		)
		(fp_line
			(start -2.667 -0.64008)
			(end -2.667 0.49022)
			(stroke
				(width 0.1524)
				(type default)
			)
			(layer "B.SilkS")
		)
		(fp_line
			(start -2.667 0.49022)
			(end -3.302 0.49022)
			(stroke
				(width 0.1524)
				(type default)
			)
			(layer "B.SilkS")
		)
		(fp_line
			(start -1.5367 -0.64008)
			(end -4.4323 -0.64008)
			(stroke
				(width 0.1524)
				(type default)
			)
			(layer "B.SilkS")
		)
		(fp_line
			(start -1.5367 4.52628)
			(end -1.5367 -0.64008)
			(stroke
				(width 0.1524)
				(type default)
			)
			(layer "B.SilkS")
		)
		(fp_circle
			(center 1.104138 -0.684784)
			(end 1.231138 -0.684784)
			(stroke
				(width 0.254)
				(type default)
			)
			(fill no)
			(layer "B.SilkS")
		)
		(fp_poly
			(pts
				(xy -0.7366 4.54152) (xy -0.7366 -0.64008) (xy -4.7244 -0.64008) (xy -5.2324 -0.64008) (xy -5.2324 4.54152)
				(xy -4.7244 4.54152)
			)
			(stroke
				(width 0)
				(type default)
			)
			(fill no)
			(layer "B.CrtYd")
		)
		(fp_line
			(start -5.2324 -0.64008)
			(end -5.2324 4.54152)
			(stroke
				(width 0.1)
				(type default)
			)
			(layer "B.Fab")
		)
		(fp_line
			(start -5.2324 4.54152)
			(end -0.7366 4.54152)
			(stroke
				(width 0.1)
				(type default)
			)
			(layer "B.Fab")
		)
		(fp_line
			(start -3.302 0.49022)
			(end -3.302 -0.64008)
			(stroke
				(width 0.1)
				(type default)
			)
			(layer "B.Fab")
		)
		(fp_line
			(start -2.667 -0.64008)
			(end -2.667 0.49022)
			(stroke
				(width 0.1)
				(type default)
			)
			(layer "B.Fab")
		)
		(fp_line
			(start -2.667 0.49022)
			(end -3.302 0.49022)
			(stroke
				(width 0.1)
				(type default)
			)
			(layer "B.Fab")
		)
		(fp_line
			(start -0.7366 -0.64008)
			(end -5.2324 -0.64008)
			(stroke
				(width 0.1)
				(type default)
			)
			(layer "B.Fab")
		)
		(fp_line
			(start -0.7366 4.54152)
			(end -0.7366 -0.64008)
			(stroke
				(width 0.1)
				(type default)
			)
			(layer "B.Fab")
		)
		(fp_circle
			(center 1.612138 -0.684784)
			(end 1.739138 -0.684784)
			(stroke
				(width 0.254)
				(type default)
			)
			(fill no)
			(layer "B.Fab")
		)
		(pad "1" smd rect
			(at 0 0 180)
			(size 2.159 0.381)
			(layers "B.Cu" "B.Mask" "B.Paste")
			(net "PU_GTL2014_1_DIR")
		)
		(pad "2" smd rect
			(at 0 0.65024 180)
			(size 2.159 0.381)
			(layers "B.Cu" "B.Mask" "B.Paste")
			(net "PWRGD_CPU0_DRAMPWROK_DEF_G")
		)
		(pad "3" smd rect
			(at 0 1.30048 180)
			(size 2.159 0.381)
			(layers "B.Cu" "B.Mask" "B.Paste")
			(net "PWRGD_CPU0_DRAMPWROK_ABC_G")
		)
		(pad "4" smd rect
			(at 0 1.95072 180)
			(size 2.159 0.381)
			(layers "B.Cu" "B.Mask" "B.Paste")
			(net "PD_GTL2014_1_VREF")
		)
		(pad "5" smd rect
			(at 0 2.60096 180)
			(size 2.159 0.381)
			(layers "B.Cu" "B.Mask" "B.Paste")
			(net "RST_CPU0_G_N")
		)
		(pad "6" smd rect
			(at 0 3.2512 180)
			(size 2.159 0.381)
			(layers "B.Cu" "B.Mask" "B.Paste")
			(net "PWRGD_CPU0_G")
		)
		(pad "7" smd rect
			(at 0 3.90144 180)
			(size 2.159 0.381)
			(layers "B.Cu" "B.Mask" "B.Paste")
			(net "GND")
		)
		(pad "8" smd rect
			(at -5.969 3.90144 180)
			(size 2.159 0.381)
			(layers "B.Cu" "B.Mask" "B.Paste")
			(net "GND")
		)
		(pad "9" smd rect
			(at -5.969 3.2512 180)
			(size 2.159 0.381)
			(layers "B.Cu" "B.Mask" "B.Paste")
			(net "PWRGD_CPU0_LVC3")
		)
		(pad "10" smd rect
			(at -5.969 2.60096 180)
			(size 2.159 0.381)
			(layers "B.Cu" "B.Mask" "B.Paste")
			(net "RST_CPU0_LVC3_N")
		)
		(pad "11" smd rect
			(at -5.969 1.95072 180)
			(size 2.159 0.381)
			(layers "B.Cu" "B.Mask" "B.Paste")
			(net "GND")
		)
		(pad "12" smd rect
			(at -5.969 1.30048 180)
			(size 2.159 0.381)
			(layers "B.Cu" "B.Mask" "B.Paste")
			(net "PWRGD_DRAMPWRGD")
		)
		(pad "13" smd rect
			(at -5.969 0.65024 180)
			(size 2.159 0.381)
			(layers "B.Cu" "B.Mask" "B.Paste")
			(net "PWRGD_DRAMPWRGD")
		)
		(pad "14" smd rect
			(at -5.969 0 180)
			(size 2.159 0.381)
			(layers "B.Cu" "B.Mask" "B.Paste")
			(net "P3V3_STBY")
		)
	)
	(footprint ""
		(layer "B.Cu")
		(at 274.881086 -85.06714)
		(property "Reference" "C5P3"
			(at 0 0 0)
			(layer "B.SilkS")
			(hide yes)
			(effects
				(font
					(size 1.27 1.27)
				)
				(justify mirror)
			)
		)
		(property "Value" ""
			(at 0 0 0)
			(layer "B.Fab")
			(effects
				(font
					(size 1.27 1.27)
				)
				(justify mirror)
			)
		)
		(duplicate_pad_numbers_are_jumpers no)
		(fp_poly
			(pts
				(xy 0.7239 -0.2159) (xy -0.7239 -0.2159) (xy -0.7239 1.9939) (xy 0.7239 1.9939)
			)
			(stroke
				(width 0)
				(type default)
			)
			(fill no)
			(layer "B.CrtYd")
		)
		(fp_line
			(start -0.7239 -0.2159)
			(end 0.7239 -0.2159)
			(stroke
				(width 0.1)
				(type default)
			)
			(layer "B.Fab")
		)
		(fp_line
			(start -0.7239 1.9939)
			(end -0.7239 -0.2159)
			(stroke
				(width 0.1)
				(type default)
			)
			(layer "B.Fab")
		)
		(fp_line
			(start 0.7239 -0.2159)
			(end 0.7239 1.9939)
			(stroke
				(width 0.1)
				(type default)
			)
			(layer "B.Fab")
		)
		(fp_line
			(start 0.7239 1.9939)
			(end -0.7239 1.9939)
			(stroke
				(width 0.1)
				(type default)
			)
			(layer "B.Fab")
		)
		(pad "1" smd rect
			(at 0 0 180)
			(size 1.27 1.016)
			(layers "B.Cu" "B.Mask" "B.Paste")
			(net "PVDDQ_DEF")
		)
		(pad "2" smd rect
			(at 0 1.778 180)
			(size 1.27 1.016)
			(layers "B.Cu" "B.Mask" "B.Paste")
			(net "GND")
		)
		(zone
			(layer "B.Cu")
			(hatch none 0.5)
			(connect_pads
				(clearance 0)
			)
			(min_thickness 0.25)
			(keepout
				(tracks not_allowed)
				(vias allowed)
				(pads allowed)
				(copperpour not_allowed)
				(footprints allowed)
			)
			(placement
				(enabled no)
				(sheetname "")
			)
			(fill
				(thermal_gap 0.5)
				(thermal_bridge_width 0.5)
				(island_removal_mode 0)
			)
			(polygon
				(pts
					(xy 275.516086 -84.55914) (xy 274.246086 -84.55914) (xy 274.246086 -83.79714) (xy 275.516086 -83.79714)
				)
			)
		)
	)
)
